# S9S_MB_2U (Grand Teton) — schematic netlist excerpt (pin names and nets, part order shuffled) for the footprints in the layout excerpt that follows; sources: Cadence DE-HDL packaged netlist, KiCad conversion of 03242023_DA0F0TMBIJ0_F0T_Motherboard_J_brd_V01_OCP.brd

C1895  Q_CAP  0.01UF 50V 10% X7R  pkg C0402  page 217 : A = P3V3_AUX_FPGA_VCCIO0 ; B = GND
R4768  Q_RES  10K 1% CHIP  pkg 0402LF  page 183 : A = E1S_0_CLK_OE_N ; B = P3V3_AUX
PC520_P1_5  Q_CAP  22UF 4V 20% X6S  pkg C0805  page 287 : A = PVCCIN_CPU1 ; B = GND

(kicad_pcb
	(version 20260206)
	(generator "pcbnew")
	(generator_version "10.0")
	(general
		(thickness 1.6)
		(legacy_teardrops no)
	)
	(paper "A4")
	(title_block
		(title "03242023_DA0F0TMBIJ0_F0T_Motherboard_J_brd_V01_OCP.brd")
		(comment 1 "Grand Teton / footprints 4533-4535 of 6105")
	)
	(layers
		(0 "F.Cu" signal "TOP")
		(4 "In1.Cu" signal "GND")
		(6 "In2.Cu" signal "IN1")
		(8 "In3.Cu" signal "GND1")
		(10 "In4.Cu" signal "IN2")
		(12 "In5.Cu" signal "GND2")
		(14 "In6.Cu" signal "IN3")
		(16 "In7.Cu" signal "GND3")
		(18 "In8.Cu" signal "VCC")
		(20 "In9.Cu" signal "VCC1")
		(22 "In10.Cu" signal "GND4")
		(24 "In11.Cu" signal "IN4")
		(26 "In12.Cu" signal "GND5")
		(28 "In13.Cu" signal "IN5")
		(30 "In14.Cu" signal "GND6")
		(32 "In15.Cu" signal "IN6")
		(34 "In16.Cu" signal "GND7")
		(2 "B.Cu" signal "BOTTOM")
		(9 "F.Adhes" user "F.Adhesive")
		(11 "B.Adhes" user "B.Adhesive")
		(13 "F.Paste" user "Package Geometry/Pastemask Top")
		(15 "B.Paste" user "Package Geometry/Pastemask Bottom")
		(5 "F.SilkS" user "Ref Des/Silkscreen Top")
		(7 "B.SilkS" user "Ref Des/Silkscreen Bottom")
		(1 "F.Mask" user "Board Geometry/Soldermask Top")
		(3 "B.Mask" user "Board Geometry/Soldermask Bottom")
		(17 "Dwgs.User" user "User.Drawings")
		(19 "Cmts.User" user "User.Comments")
		(21 "Eco1.User" user "User.Eco1")
		(23 "Eco2.User" user "User.Eco2")
		(25 "Edge.Cuts" user "Board Geometry/Outline")
		(27 "Margin" user)
		(31 "F.CrtYd" user "Package Geometry/Place Bound Top")
		(29 "B.CrtYd" user "Package Geometry/Place Bound Bottom")
		(35 "F.Fab" user "Ref Des/Assembly Top")
		(33 "B.Fab" user "Ref Des/Assembly Bottom")
	)
	(footprint ""
		(layer "B.Cu")
		(at 126.041912 -328.298048 -90)
		(property "Reference" "PC520_P1_5"
			(at 0 0 90)
			(layer "B.SilkS")
			(hide yes)
			(effects
				(font
					(size 1.27 1.27)
				)
				(justify mirror)
			)
		)
		(property "Value" ""
			(at 0 0 90)
			(layer "B.Fab")
			(effects
				(font
					(size 1.27 1.27)
				)
				(justify mirror)
			)
		)
		(duplicate_pad_numbers_are_jumpers no)
		(fp_line
			(start -1.524 0.762)
			(end 1.524 0.762)
			(stroke
				(width 0.1524)
				(type default)
			)
			(layer "B.SilkS")
		)
		(fp_line
			(start 1.524 0.762)
			(end 1.524 -0.762)
			(stroke
				(width 0.1524)
				(type default)
			)
			(layer "B.SilkS")
		)
		(fp_line
			(start -1.524 -0.762)
			(end -1.524 0.762)
			(stroke
				(width 0.1524)
				(type default)
			)
			(layer "B.SilkS")
		)
		(fp_line
			(start 1.524 -0.762)
			(end -1.524 -0.762)
			(stroke
				(width 0.1524)
				(type default)
			)
			(layer "B.SilkS")
		)
		(fp_line
			(start -1.1049 0.724916)
			(end -1.1049 -0.724916)
			(stroke
				(width 0.1)
				(type default)
			)
			(layer "B.Fab")
		)
		(fp_line
			(start 1.1049 0.724916)
			(end -1.1049 0.724916)
			(stroke
				(width 0.1)
				(type default)
			)
			(layer "B.Fab")
		)
		(fp_line
			(start -1.1049 -0.724916)
			(end 1.1049 -0.724916)
			(stroke
				(width 0.1)
				(type default)
			)
			(layer "B.Fab")
		)
		(fp_line
			(start 1.1049 -0.724916)
			(end 1.1049 0.724916)
			(stroke
				(width 0.1)
				(type default)
			)
			(layer "B.Fab")
		)
		(pad "1" smd rect
			(at 0.889 0 270)
			(size 1.016 1.27)
			(layers "B.Cu" "B.Mask" "B.Paste")
			(net "PVCCIN_CPU1")
		)
		(pad "2" smd rect
			(at -0.889 0 270)
			(size 1.016 1.27)
			(layers "B.Cu" "B.Mask" "B.Paste")
			(net "GND")
		)
	)
	(footprint ""
		(layer "B.Cu")
		(at 309.5498 -34.1884 180)
		(property "Reference" "R4768"
			(at 0 0 0)
			(layer "B.SilkS")
			(hide yes)
			(effects
				(font
					(size 1.27 1.27)
				)
				(justify mirror)
			)
		)
		(property "Value" ""
			(at 0 0 0)
			(layer "B.Fab")
			(effects
				(font
					(size 1.27 1.27)
				)
				(justify mirror)
			)
		)
		(duplicate_pad_numbers_are_jumpers no)
		(fp_line
			(start 0.7874 0.4064)
			(end 0.7874 -0.4064)
			(stroke
				(width 0.1524)
				(type default)
			)
			(layer "B.SilkS")
		)
		(fp_line
			(start 0.7874 -0.4064)
			(end -0.7874 -0.4064)
			(stroke
				(width 0.1524)
				(type default)
			)
			(layer "B.SilkS")
		)
		(fp_line
			(start -0.7874 0.4064)
			(end 0.7874 0.4064)
			(stroke
				(width 0.1524)
				(type default)
			)
			(layer "B.SilkS")
		)
		(fp_line
			(start -0.7874 -0.4064)
			(end -0.7874 0.4064)
			(stroke
				(width 0.1524)
				(type default)
			)
			(layer "B.SilkS")
		)
		(fp_line
			(start 0.67945 0.3048)
			(end 0.67945 -0.305054)
			(stroke
				(width 0.1)
				(type default)
			)
			(layer "B.Fab")
		)
		(fp_line
			(start 0.67945 -0.305054)
			(end 0.12065 -0.305054)
			(stroke
				(width 0.1)
				(type default)
			)
			(layer "B.Fab")
		)
		(fp_line
			(start 0.12065 0.3048)
			(end 0.67945 0.3048)
			(stroke
				(width 0.1)
				(type default)
			)
			(layer "B.Fab")
		)
		(fp_line
			(start 0.12065 0.2794)
			(end 0.12065 0.3048)
			(stroke
				(width 0.1)
				(type default)
			)
			(layer "B.Fab")
		)
		(fp_line
			(start 0.12065 -0.2794)
			(end -0.12065 -0.2794)
			(stroke
				(width 0.1)
				(type default)
			)
			(layer "B.Fab")
		)
		(fp_line
			(start 0.12065 -0.305054)
			(end 0.12065 -0.2794)
			(stroke
				(width 0.1)
				(type default)
			)
			(layer "B.Fab")
		)
		(fp_line
			(start -0.120396 0.3048)
			(end -0.120396 0.2794)
			(stroke
				(width 0.1)
				(type default)
			)
			(layer "B.Fab")
		)
		(fp_line
			(start -0.120396 0.2794)
			(end 0.12065 0.2794)
			(stroke
				(width 0.1)
				(type default)
			)
			(layer "B.Fab")
		)
		(fp_line
			(start -0.12065 -0.2794)
			(end -0.12065 -0.3048)
			(stroke
				(width 0.1)
				(type default)
			)
			(layer "B.Fab")
		)
		(fp_line
			(start -0.12065 -0.3048)
			(end -0.67945 -0.3048)
			(stroke
				(width 0.1)
				(type default)
			)
			(layer "B.Fab")
		)
		(fp_line
			(start -0.67945 0.3048)
			(end -0.120396 0.3048)
			(stroke
				(width 0.1)
				(type default)
			)
			(layer "B.Fab")
		)
		(fp_line
			(start -0.67945 -0.3048)
			(end -0.67945 0.3048)
			(stroke
				(width 0.1)
				(type default)
			)
			(layer "B.Fab")
		)
		(pad "1" smd circle
			(at 0.40005 0)
			(size 0 0)
			(layers "B.Cu" "B.Mask" "B.Paste")
			(net "E1S_0_CLK_OE_N")
		)
		(pad "2" smd circle
			(at -0.40005 0)
			(size 0 0)
			(layers "B.Cu" "B.Mask" "B.Paste")
			(net "P3V3_AUX")
		)
	)
	(footprint ""
		(layer "B.Cu")
		(at 171.755562 -113.37544 90)
		(property "Reference" "C1895"
			(at 0 0 90)
			(layer "B.SilkS")
			(hide yes)
			(effects
				(font
					(size 1.27 1.27)
				)
				(justify mirror)
			)
		)
		(property "Value" ""
			(at 0 0 90)
			(layer "B.Fab")
			(effects
				(font
					(size 1.27 1.27)
				)
				(justify mirror)
			)
		)
		(duplicate_pad_numbers_are_jumpers no)
		(fp_line
			(start 0.69215 -0.2921)
			(end -0.69215 -0.2921)
			(stroke
				(width 0.1524)
				(type default)
			)
			(layer "B.SilkS")
		)
		(fp_line
			(start -0.69215 -0.2921)
			(end -0.69215 0.2921)
			(stroke
				(width 0.1524)
				(type default)
			)
			(layer "B.SilkS")
		)
		(fp_line
			(start 0.69215 0.2921)
			(end 0.69215 -0.2921)
			(stroke
				(width 0.1524)
				(type default)
			)
			(layer "B.SilkS")
		)
		(fp_line
			(start -0.69215 0.2921)
			(end 0.69215 0.2921)
			(stroke
				(width 0.1524)
				(type default)
			)
			(layer "B.SilkS")
		)
		(fp_line
			(start 0.51435 -0.2794)
			(end -0.51435 -0.2794)
			(stroke
				(width 0.1)
				(type default)
			)
			(layer "B.Fab")
		)
		(fp_line
			(start -0.51435 -0.2794)
			(end -0.51435 0.2794)
			(stroke
				(width 0.1)
				(type default)
			)
			(layer "B.Fab")
		)
		(fp_line
			(start 0.51435 0.2794)
			(end 0.51435 -0.2794)
			(stroke
				(width 0.1)
				(type default)
			)
			(layer "B.Fab")
		)
		(fp_line
			(start -0.51435 0.2794)
			(end 0.51435 0.2794)
			(stroke
				(width 0.1)
				(type default)
			)
			(layer "B.Fab")
		)
		(pad "1" smd circle
			(at 0.40005 0 270)
			(size 0 0)
			(layers "B.Cu" "B.Mask" "B.Paste")
			(net "P3V3_AUX_FPGA_VCCIO0")
		)
		(pad "2" smd circle
			(at -0.40005 0 270)
			(size 0 0)
			(layers "B.Cu" "B.Mask" "B.Paste")
			(net "GND")
		)
		(zone
			(layer "B.Cu")
			(hatch none 0.5)
			(connect_pads
				(clearance 0)
			)
			(min_thickness 0.25)
			(keepout
				(tracks not_allowed)
				(vias allowed)
				(pads allowed)
				(copperpour not_allowed)
				(footprints allowed)
			)
			(placement
				(enabled no)
				(sheetname "")
			)
			(fill
				(thermal_gap 0.5)
				(thermal_bridge_width 0.5)
				(island_removal_mode 0)
			)
			(polygon
				(pts
					(xy 171.843192 -113.56594) (xy 171.901358 -113.4745) (xy 171.901358 -113.27511) (xy 171.843192 -113.18494)
					(xy 171.667932 -113.18494) (xy 171.609512 -113.27511) (xy 171.609512 -113.4745) (xy 171.667678 -113.56594)
				)
			)
		)
	)
)
